(kicad_pcb
	(version 20260206)
	(generator "pcbnew")
	(generator_version "10.0")
	(general
		(thickness 1.6)
		(legacy_teardrops no)
	)
	(paper "A4")
	(title_block
		(title "03242023_DA0F0TMBIJ0_F0T_Motherboard_J_brd_V01_OCP.brd")
		(comment 1 "Grand Teton / footprints 5614-5618 of 6105")
	)
	(layers
		(0 "F.Cu" signal "TOP")
		(4 "In1.Cu" signal "GND")
		(6 "In2.Cu" signal "IN1")
		(8 "In3.Cu" signal "GND1")
		(10 "In4.Cu" signal "IN2")
		(12 "In5.Cu" signal "GND2")
		(14 "In6.Cu" signal "IN3")
		(16 "In7.Cu" signal "GND3")
		(18 "In8.Cu" signal "VCC")
		(20 "In9.Cu" signal "VCC1")
		(22 "In10.Cu" signal "GND4")
		(24 "In11.Cu" signal "IN4")
		(26 "In12.Cu" signal "GND5")
		(28 "In13.Cu" signal "IN5")
		(30 "In14.Cu" signal "GND6")
		(32 "In15.Cu" signal "IN6")
		(34 "In16.Cu" signal "GND7")
		(2 "B.Cu" signal "BOTTOM")
		(9 "F.Adhes" user "F.Adhesive")
		(11 "B.Adhes" user "B.Adhesive")
		(13 "F.Paste" user "Package Geometry/Pastemask Top")
		(15 "B.Paste" user "Package Geometry/Pastemask Bottom")
		(5 "F.SilkS" user "Ref Des/Silkscreen Top")
		(7 "B.SilkS" user "Ref Des/Silkscreen Bottom")
		(1 "F.Mask" user "Board Geometry/Soldermask Top")
		(3 "B.Mask" user "Board Geometry/Soldermask Bottom")
		(17 "Dwgs.User" user "User.Drawings")
		(19 "Cmts.User" user "User.Comments")
		(21 "Eco1.User" user "User.Eco1")
		(23 "Eco2.User" user "User.Eco2")
		(25 "Edge.Cuts" user "Board Geometry/Outline")
		(27 "Margin" user)
		(31 "F.CrtYd" user "Package Geometry/Place Bound Top")
		(29 "B.CrtYd" user "Package Geometry/Place Bound Bottom")
		(35 "F.Fab" user "Ref Des/Assembly Top")
		(33 "B.Fab" user "Ref Des/Assembly Bottom")
	)
	(footprint ""
		(layer "B.Cu")
		(at 263.2583 -419.164008 90)
		(property "Reference" "PD16"
			(at 4.59994 4.264152 90)
			(unlocked yes)
			(layer "B.SilkS")
			(effects
				(font
					(size 0.7874 0.5842)
					(thickness 0.1524)
				)
				(justify left mirror)
			)
		)
		(property "Value" ""
			(at 0 0 90)
			(layer "B.Fab")
			(effects
				(font
					(size 1.27 1.27)
				)
				(justify mirror)
			)
		)
		(duplicate_pad_numbers_are_jumpers no)
		(fp_line
			(start 4.664456 -3.109976)
			(end -4.743704 -3.109976)
			(stroke
				(width 0.1524)
				(type default)
			)
			(layer "B.SilkS")
		)
		(fp_line
			(start -4.183126 -3.109976)
			(end -4.794504 -3.109976)
			(stroke
				(width 0.1524)
				(type default)
			)
			(layer "B.SilkS")
		)
		(fp_line
			(start -4.511802 -3.109976)
			(end -4.207002 -3.109976)
			(stroke
				(width 0.1524)
				(type default)
			)
			(layer "B.SilkS")
		)
		(fp_line
			(start -4.6101 -3.109976)
			(end -4.283202 -3.109976)
			(stroke
				(width 0.1524)
				(type default)
			)
			(layer "B.SilkS")
		)
		(fp_line
			(start -4.695444 -3.109976)
			(end -4.695444 3.109976)
			(stroke
				(width 0.1524)
				(type default)
			)
			(layer "B.SilkS")
		)
		(fp_line
			(start -4.70535 -3.109976)
			(end -4.70535 3.109976)
			(stroke
				(width 0.1524)
				(type default)
			)
			(layer "B.SilkS")
		)
		(fp_line
			(start -4.70535 -3.109976)
			(end -4.70535 3.109976)
			(stroke
				(width 0.1524)
				(type default)
			)
			(layer "B.SilkS")
		)
		(fp_line
			(start -4.70535 -3.109976)
			(end -4.70535 3.109976)
			(stroke
				(width 0.1524)
				(type default)
			)
			(layer "B.SilkS")
		)
		(fp_line
			(start -4.805426 -3.109976)
			(end -4.805426 3.109976)
			(stroke
				(width 0.1524)
				(type default)
			)
			(layer "B.SilkS")
		)
		(fp_line
			(start -4.932426 -3.109976)
			(end -4.932426 3.109976)
			(stroke
				(width 0.1524)
				(type default)
			)
			(layer "B.SilkS")
		)
		(fp_line
			(start -5.008626 -3.109976)
			(end -5.008626 3.109976)
			(stroke
				(width 0.1524)
				(type default)
			)
			(layer "B.SilkS")
		)
		(fp_line
			(start -5.110226 -3.109976)
			(end -5.110226 3.109976)
			(stroke
				(width 0.1524)
				(type default)
			)
			(layer "B.SilkS")
		)
		(fp_line
			(start -5.211826 -3.109976)
			(end -5.211826 3.109976)
			(stroke
				(width 0.1524)
				(type default)
			)
			(layer "B.SilkS")
		)
		(fp_line
			(start -5.262626 -3.109976)
			(end -5.262626 3.109976)
			(stroke
				(width 0.1524)
				(type default)
			)
			(layer "B.SilkS")
		)
		(fp_line
			(start -5.313426 -3.109976)
			(end -5.313426 3.109976)
			(stroke
				(width 0.1524)
				(type default)
			)
			(layer "B.SilkS")
		)
		(fp_line
			(start -5.4102 -3.109976)
			(end -4.783074 -3.109976)
			(stroke
				(width 0.1524)
				(type default)
			)
			(layer "B.SilkS")
		)
		(fp_line
			(start 0.508 -1.016)
			(end -0.762 0)
			(stroke
				(width 0.1524)
				(type default)
			)
			(layer "B.SilkS")
		)
		(fp_line
			(start 1.0668 0)
			(end 0.6096 0)
			(stroke
				(width 0.1524)
				(type default)
			)
			(layer "B.SilkS")
		)
		(fp_line
			(start -0.762 0)
			(end -1.2192 0)
			(stroke
				(width 0.1524)
				(type default)
			)
			(layer "B.SilkS")
		)
		(fp_line
			(start -0.762 0)
			(end 0.508 1.016)
			(stroke
				(width 0.1524)
				(type default)
			)
			(layer "B.SilkS")
		)
		(fp_line
			(start 0.508 1.016)
			(end 0.508 -1.016)
			(stroke
				(width 0.1524)
				(type default)
			)
			(layer "B.SilkS")
		)
		(fp_line
			(start -0.762 1.27)
			(end -0.762 -1.27)
			(stroke
				(width 0.1524)
				(type default)
			)
			(layer "B.SilkS")
		)
		(fp_line
			(start -4.715002 3.035554)
			(end -4.7117 2.984754)
			(stroke
				(width 0.1524)
				(type default)
			)
			(layer "B.SilkS")
		)
		(fp_line
			(start 4.664456 3.109976)
			(end 4.664456 -3.109976)
			(stroke
				(width 0.1524)
				(type default)
			)
			(layer "B.SilkS")
		)
		(fp_line
			(start -4.156202 3.109976)
			(end -4.183126 3.109976)
			(stroke
				(width 0.1524)
				(type default)
			)
			(layer "B.SilkS")
		)
		(fp_line
			(start -4.743704 3.109976)
			(end -4.6101 3.109976)
			(stroke
				(width 0.1524)
				(type default)
			)
			(layer "B.SilkS")
		)
		(fp_line
			(start -4.743704 3.109976)
			(end -5.4102 3.109976)
			(stroke
				(width 0.1524)
				(type default)
			)
			(layer "B.SilkS")
		)
		(fp_line
			(start -4.769104 3.109976)
			(end 4.664456 3.109976)
			(stroke
				(width 0.1524)
				(type default)
			)
			(layer "B.SilkS")
		)
		(fp_line
			(start -4.794504 3.109976)
			(end -3.554984 3.109976)
			(stroke
				(width 0.1524)
				(type default)
			)
			(layer "B.SilkS")
		)
		(fp_line
			(start -5.4102 3.109976)
			(end -5.4102 -3.109976)
			(stroke
				(width 0.1524)
				(type default)
			)
			(layer "B.SilkS")
		)
		(fp_line
			(start 4.065016 -3.109976)
			(end -4.065016 -3.109976)
			(stroke
				(width 0.1)
				(type default)
			)
			(layer "B.Fab")
		)
		(fp_line
			(start -4.065016 -3.109976)
			(end -4.065016 3.109976)
			(stroke
				(width 0.1)
				(type default)
			)
			(layer "B.Fab")
		)
		(fp_line
			(start 4.065016 3.109976)
			(end 4.065016 -3.109976)
			(stroke
				(width 0.1)
				(type default)
			)
			(layer "B.Fab")
		)
		(fp_line
			(start -4.065016 3.109976)
			(end 4.065016 3.109976)
			(stroke
				(width 0.1)
				(type default)
			)
			(layer "B.Fab")
		)
		(fp_text user "+"
			(at 4.5974 0.24765 270)
			(unlocked yes)
			(layer "B.SilkS")
			(effects
				(font
					(size 1.905 1.4224)
					(thickness 0.1524)
				)
				(justify left mirror)
			)
		)
		(fp_text user "-"
			(at -6.643624 0.40005 270)
			(unlocked yes)
			(layer "B.SilkS")
			(effects
				(font
					(size 1.905 1.4224)
					(thickness 0.1524)
				)
				(justify left mirror)
			)
		)
		(fp_text user "+"
			(at 4.5974 0.24765 270)
			(unlocked yes)
			(layer "B.Fab")
			(effects
				(font
					(size 1.905 1.4224)
					(thickness 0.1524)
				)
				(justify left mirror)
			)
		)
		(fp_text user "-"
			(at -6.643624 0.40005 270)
			(unlocked yes)
			(layer "B.Fab")
			(effects
				(font
					(size 1.905 1.4224)
					(thickness 0.1524)
				)
				(justify left mirror)
			)
		)
		(pad "A" smd rect
			(at 3.299968 0 90)
			(size 2.413 3.302)
			(layers "B.Cu" "B.Mask" "B.Paste")
			(net "GND")
		)
		(pad "C" smd rect
			(at -3.299968 0 90)
			(size 2.413 3.302)
			(layers "B.Cu" "B.Mask" "B.Paste")
			(net "P12V_PSU_FUSE")
		)
	)
	(footprint ""
		(layer "B.Cu")
		(at 305.533298 -152.179782 180)
		(property "Reference" "R694"
			(at 0 0 0)
			(layer "B.SilkS")
			(hide yes)
			(effects
				(font
					(size 1.27 1.27)
				)
				(justify mirror)
			)
		)
		(property "Value" ""
			(at 0 0 0)
			(layer "B.Fab")
			(effects
				(font
					(size 1.27 1.27)
				)
				(justify mirror)
			)
		)
		(duplicate_pad_numbers_are_jumpers no)
		(fp_line
			(start 0.7874 0.4064)
			(end 0.7874 -0.4064)
			(stroke
				(width 0.1524)
				(type default)
			)
			(layer "B.SilkS")
		)
		(fp_line
			(start 0.7874 -0.4064)
			(end -0.7874 -0.4064)
			(stroke
				(width 0.1524)
				(type default)
			)
			(layer "B.SilkS")
		)
		(fp_line
			(start -0.7874 0.4064)
			(end 0.7874 0.4064)
			(stroke
				(width 0.1524)
				(type default)
			)
			(layer "B.SilkS")
		)
		(fp_line
			(start -0.7874 -0.4064)
			(end -0.7874 0.4064)
			(stroke
				(width 0.1524)
				(type default)
			)
			(layer "B.SilkS")
		)
		(fp_line
			(start 0.67945 0.3048)
			(end 0.67945 -0.305054)
			(stroke
				(width 0.1)
				(type default)
			)
			(layer "B.Fab")
		)
		(fp_line
			(start 0.67945 -0.305054)
			(end 0.12065 -0.305054)
			(stroke
				(width 0.1)
				(type default)
			)
			(layer "B.Fab")
		)
		(fp_line
			(start 0.12065 0.3048)
			(end 0.67945 0.3048)
			(stroke
				(width 0.1)
				(type default)
			)
			(layer "B.Fab")
		)
		(fp_line
			(start 0.12065 0.2794)
			(end 0.12065 0.3048)
			(stroke
				(width 0.1)
				(type default)
			)
			(layer "B.Fab")
		)
		(fp_line
			(start 0.12065 -0.2794)
			(end -0.12065 -0.2794)
			(stroke
				(width 0.1)
				(type default)
			)
			(layer "B.Fab")
		)
		(fp_line
			(start 0.12065 -0.305054)
			(end 0.12065 -0.2794)
			(stroke
				(width 0.1)
				(type default)
			)
			(layer "B.Fab")
		)
		(fp_line
			(start -0.120396 0.3048)
			(end -0.120396 0.2794)
			(stroke
				(width 0.1)
				(type default)
			)
			(layer "B.Fab")
		)
		(fp_line
			(start -0.120396 0.2794)
			(end 0.12065 0.2794)
			(stroke
				(width 0.1)
				(type default)
			)
			(layer "B.Fab")
		)
		(fp_line
			(start -0.12065 -0.2794)
			(end -0.12065 -0.3048)
			(stroke
				(width 0.1)
				(type default)
			)
			(layer "B.Fab")
		)
		(fp_line
			(start -0.12065 -0.3048)
			(end -0.67945 -0.3048)
			(stroke
				(width 0.1)
				(type default)
			)
			(layer "B.Fab")
		)
		(fp_line
			(start -0.67945 0.3048)
			(end -0.120396 0.3048)
			(stroke
				(width 0.1)
				(type default)
			)
			(layer "B.Fab")
		)
		(fp_line
			(start -0.67945 -0.3048)
			(end -0.67945 0.3048)
			(stroke
				(width 0.1)
				(type default)
			)
			(layer "B.Fab")
		)
		(pad "1" smd circle
			(at 0.40005 0)
			(size 0 0)
			(layers "B.Cu" "B.Mask" "B.Paste")
			(net "I3C_SPD_DDREFGH_CPU0_LVC1_R_SDA")
		)
		(pad "2" smd circle
			(at -0.40005 0)
			(size 0 0)
			(layers "B.Cu" "B.Mask" "B.Paste")
			(net "I3C_SPD_DDREFGH_CPU0_LVC1_SDA")
		)
	)
	(footprint ""
		(layer "B.Cu")
		(at 297.942 -258.155948)
		(property "Reference" "R185"
			(at 0 0 0)
			(layer "B.SilkS")
			(hide yes)
			(effects
				(font
					(size 1.27 1.27)
				)
				(justify mirror)
			)
		)
		(property "Value" ""
			(at 0 0 0)
			(layer "B.Fab")
			(effects
				(font
					(size 1.27 1.27)
				)
				(justify mirror)
			)
		)
		(duplicate_pad_numbers_are_jumpers no)
		(fp_line
			(start -0.7874 -0.4064)
			(end -0.7874 0.4064)
			(stroke
				(width 0.1524)
				(type default)
			)
			(layer "B.SilkS")
		)
		(fp_line
			(start -0.7874 0.4064)
			(end 0.7874 0.4064)
			(stroke
				(width 0.1524)
				(type default)
			)
			(layer "B.SilkS")
		)
		(fp_line
			(start 0.7874 -0.4064)
			(end -0.7874 -0.4064)
			(stroke
				(width 0.1524)
				(type default)
			)
			(layer "B.SilkS")
		)
		(fp_line
			(start 0.7874 0.4064)
			(end 0.7874 -0.4064)
			(stroke
				(width 0.1524)
				(type default)
			)
			(layer "B.SilkS")
		)
		(fp_line
			(start -0.67945 -0.3048)
			(end -0.67945 0.3048)
			(stroke
				(width 0.1)
				(type default)
			)
			(layer "B.Fab")
		)
		(fp_line
			(start -0.67945 0.3048)
			(end -0.120396 0.3048)
			(stroke
				(width 0.1)
				(type default)
			)
			(layer "B.Fab")
		)
		(fp_line
			(start -0.12065 -0.3048)
			(end -0.67945 -0.3048)
			(stroke
				(width 0.1)
				(type default)
			)
			(layer "B.Fab")
		)
		(fp_line
			(start -0.12065 -0.2794)
			(end -0.12065 -0.3048)
			(stroke
				(width 0.1)
				(type default)
			)
			(layer "B.Fab")
		)
		(fp_line
			(start -0.120396 0.2794)
			(end 0.12065 0.2794)
			(stroke
				(width 0.1)
				(type default)
			)
			(layer "B.Fab")
		)
		(fp_line
			(start -0.120396 0.3048)
			(end -0.120396 0.2794)
			(stroke
				(width 0.1)
				(type default)
			)
			(layer "B.Fab")
		)
		(fp_line
			(start 0.12065 -0.305054)
			(end 0.12065 -0.2794)
			(stroke
				(width 0.1)
				(type default)
			)
			(layer "B.Fab")
		)
		(fp_line
			(start 0.12065 -0.2794)
			(end -0.12065 -0.2794)
			(stroke
				(width 0.1)
				(type default)
			)
			(layer "B.Fab")
		)
		(fp_line
			(start 0.12065 0.2794)
			(end 0.12065 0.3048)
			(stroke
				(width 0.1)
				(type default)
			)
			(layer "B.Fab")
		)
		(fp_line
			(start 0.12065 0.3048)
			(end 0.67945 0.3048)
			(stroke
				(width 0.1)
				(type default)
			)
			(layer "B.Fab")
		)
		(fp_line
			(start 0.67945 -0.305054)
			(end 0.12065 -0.305054)
			(stroke
				(width 0.1)
				(type default)
			)
			(layer "B.Fab")
		)
		(fp_line
			(start 0.67945 0.3048)
			(end 0.67945 -0.305054)
			(stroke
				(width 0.1)
				(type default)
			)
			(layer "B.Fab")
		)
		(pad "1" smd circle
			(at 0.40005 0 180)
			(size 0 0)
			(layers "B.Cu" "B.Mask" "B.Paste")
			(net "RST_CPU0_BUF_R_N")
		)
		(pad "2" smd circle
			(at -0.40005 0 180)
			(size 0 0)
			(layers "B.Cu" "B.Mask" "B.Paste")
			(net "PVNN_TERM_CPU0")
		)
	)
	(footprint ""
		(layer "B.Cu")
		(at 460.075788 -383.650998 180)
		(property "Reference" "R2356"
			(at 0 0 0)
			(layer "B.SilkS")
			(hide yes)
			(effects
				(font
					(size 1.27 1.27)
				)
				(justify mirror)
			)
		)
		(property "Value" ""
			(at 0 0 0)
			(layer "B.Fab")
			(effects
				(font
					(size 1.27 1.27)
				)
				(justify mirror)
			)
		)
		(duplicate_pad_numbers_are_jumpers no)
		(fp_line
			(start 0.7874 0.4064)
			(end 0.7874 -0.4064)
			(stroke
				(width 0.1524)
				(type default)
			)
			(layer "B.SilkS")
		)
		(fp_line
			(start 0.7874 -0.4064)
			(end -0.7874 -0.4064)
			(stroke
				(width 0.1524)
				(type default)
			)
			(layer "B.SilkS")
		)
		(fp_line
			(start -0.7874 0.4064)
			(end 0.7874 0.4064)
			(stroke
				(width 0.1524)
				(type default)
			)
			(layer "B.SilkS")
		)
		(fp_line
			(start -0.7874 -0.4064)
			(end -0.7874 0.4064)
			(stroke
				(width 0.1524)
				(type default)
			)
			(layer "B.SilkS")
		)
		(fp_line
			(start 0.67945 0.3048)
			(end 0.67945 -0.305054)
			(stroke
				(width 0.1)
				(type default)
			)
			(layer "B.Fab")
		)
		(fp_line
			(start 0.67945 -0.305054)
			(end 0.12065 -0.305054)
			(stroke
				(width 0.1)
				(type default)
			)
			(layer "B.Fab")
		)
		(fp_line
			(start 0.12065 0.3048)
			(end 0.67945 0.3048)
			(stroke
				(width 0.1)
				(type default)
			)
			(layer "B.Fab")
		)
		(fp_line
			(start 0.12065 0.2794)
			(end 0.12065 0.3048)
			(stroke
				(width 0.1)
				(type default)
			)
			(layer "B.Fab")
		)
		(fp_line
			(start 0.12065 -0.2794)
			(end -0.12065 -0.2794)
			(stroke
				(width 0.1)
				(type default)
			)
			(layer "B.Fab")
		)
		(fp_line
			(start 0.12065 -0.305054)
			(end 0.12065 -0.2794)
			(stroke
				(width 0.1)
				(type default)
			)
			(layer "B.Fab")
		)
		(fp_line
			(start -0.120396 0.3048)
			(end -0.120396 0.2794)
			(stroke
				(width 0.1)
				(type default)
			)
			(layer "B.Fab")
		)
		(fp_line
			(start -0.120396 0.2794)
			(end 0.12065 0.2794)
			(stroke
				(width 0.1)
				(type default)
			)
			(layer "B.Fab")
		)
		(fp_line
			(start -0.12065 -0.2794)
			(end -0.12065 -0.3048)
			(stroke
				(width 0.1)
				(type default)
			)
			(layer "B.Fab")
		)
		(fp_line
			(start -0.12065 -0.3048)
			(end -0.67945 -0.3048)
			(stroke
				(width 0.1)
				(type default)
			)
			(layer "B.Fab")
		)
		(fp_line
			(start -0.67945 0.3048)
			(end -0.120396 0.3048)
			(stroke
				(width 0.1)
				(type default)
			)
			(layer "B.Fab")
		)
		(fp_line
			(start -0.67945 -0.3048)
			(end -0.67945 0.3048)
			(stroke
				(width 0.1)
				(type default)
			)
			(layer "B.Fab")
		)
		(pad "1" smd circle
			(at 0.40005 0)
			(size 0 0)
			(layers "B.Cu" "B.Mask" "B.Paste")
			(net "P5V_AUX_VCC")
		)
		(pad "2" smd circle
			(at -0.40005 0)
			(size 0 0)
			(layers "B.Cu" "B.Mask" "B.Paste")
			(net "PWRGD_P5V_AUX_R")
		)
	)
	(footprint ""
		(layer "B.Cu")
		(at 363.135418 -294.009826 180)
		(property "Reference" "C377"
			(at 0 0 0)
			(layer "B.SilkS")
			(hide yes)
			(effects
				(font
					(size 1.27 1.27)
				)
				(justify mirror)
			)
		)
		(property "Value" ""
			(at 0 0 0)
			(layer "B.Fab")
			(effects
				(font
					(size 1.27 1.27)
				)
				(justify mirror)
			)
		)
		(duplicate_pad_numbers_are_jumpers no)
		(fp_line
			(start 1.524 0.762)
			(end 1.524 -0.762)
			(stroke
				(width 0.1524)
				(type default)
			)
			(layer "B.SilkS")
		)
		(fp_line
			(start 1.524 -0.762)
			(end -1.524 -0.762)
			(stroke
				(width 0.1524)
				(type default)
			)
			(layer "B.SilkS")
		)
		(fp_line
			(start -1.524 0.762)
			(end 1.524 0.762)
			(stroke
				(width 0.1524)
				(type default)
			)
			(layer "B.SilkS")
		)
		(fp_line
			(start -1.524 -0.762)
			(end -1.524 0.762)
			(stroke
				(width 0.1524)
				(type default)
			)
			(layer "B.SilkS")
		)
		(fp_line
			(start 1.1049 0.724916)
			(end -1.1049 0.724916)
			(stroke
				(width 0.1)
				(type default)
			)
			(layer "B.Fab")
		)
		(fp_line
			(start 1.1049 -0.724916)
			(end 1.1049 0.724916)
			(stroke
				(width 0.1)
				(type default)
			)
			(layer "B.Fab")
		)
		(fp_line
			(start -1.1049 0.724916)
			(end -1.1049 -0.724916)
			(stroke
				(width 0.1)
				(type default)
			)
			(layer "B.Fab")
		)
		(fp_line
			(start -1.1049 -0.724916)
			(end 1.1049 -0.724916)
			(stroke
				(width 0.1)
				(type default)
			)
			(layer "B.Fab")
		)
		(pad "1" smd rect
			(at 0.889 0 180)
			(size 1.016 1.27)
			(layers "B.Cu" "B.Mask" "B.Paste")
			(net "PVCCIN_CPU0")
		)
		(pad "2" smd rect
			(at -0.889 0 180)
			(size 1.016 1.27)
			(layers "B.Cu" "B.Mask" "B.Paste")
			(net "GND")
		)
	)
)
